(kicad_pcb
	(version 20260206)
	(generator "pcbnew")
	(generator_version "10.0")
	(general
		(thickness 1.6)
		(legacy_teardrops no)
	)
	(paper "A4")
	(title_block
		(title "03242023_DA0F0TMBIJ0_F0T_Motherboard_J_brd_V01_OCP.brd")
		(comment 1 "Grand Teton / footprints 3269-3274 of 6105")
	)
	(layers
		(0 "F.Cu" signal "TOP")
		(4 "In1.Cu" signal "GND")
		(6 "In2.Cu" signal "IN1")
		(8 "In3.Cu" signal "GND1")
		(10 "In4.Cu" signal "IN2")
		(12 "In5.Cu" signal "GND2")
		(14 "In6.Cu" signal "IN3")
		(16 "In7.Cu" signal "GND3")
		(18 "In8.Cu" signal "VCC")
		(20 "In9.Cu" signal "VCC1")
		(22 "In10.Cu" signal "GND4")
		(24 "In11.Cu" signal "IN4")
		(26 "In12.Cu" signal "GND5")
		(28 "In13.Cu" signal "IN5")
		(30 "In14.Cu" signal "GND6")
		(32 "In15.Cu" signal "IN6")
		(34 "In16.Cu" signal "GND7")
		(2 "B.Cu" signal "BOTTOM")
		(9 "F.Adhes" user "F.Adhesive")
		(11 "B.Adhes" user "B.Adhesive")
		(13 "F.Paste" user "Package Geometry/Pastemask Top")
		(15 "B.Paste" user "Package Geometry/Pastemask Bottom")
		(5 "F.SilkS" user "Ref Des/Silkscreen Top")
		(7 "B.SilkS" user "Ref Des/Silkscreen Bottom")
		(1 "F.Mask" user "Board Geometry/Soldermask Top")
		(3 "B.Mask" user "Board Geometry/Soldermask Bottom")
		(17 "Dwgs.User" user "User.Drawings")
		(19 "Cmts.User" user "User.Comments")
		(21 "Eco1.User" user "User.Eco1")
		(23 "Eco2.User" user "User.Eco2")
		(25 "Edge.Cuts" user "Board Geometry/Outline")
		(27 "Margin" user)
		(31 "F.CrtYd" user "Package Geometry/Place Bound Top")
		(29 "B.CrtYd" user "Package Geometry/Place Bound Bottom")
		(35 "F.Fab" user "Ref Des/Assembly Top")
		(33 "B.Fab" user "Ref Des/Assembly Bottom")
	)
	(footprint ""
		(layer "F.Cu")
		(at 320.95567 -338.218526 90)
		(property "Reference" "PL105"
			(at -4.399788 -2.95021 0)
			(unlocked yes)
			(layer "F.SilkS")
			(effects
				(font
					(size 0.7874 0.5842)
					(thickness 0.1524)
				)
				(justify left)
			)
		)
		(property "Value" ""
			(at 0 0 90)
			(layer "F.Fab")
			(effects
				(font
					(size 1.27 1.27)
				)
			)
		)
		(duplicate_pad_numbers_are_jumpers no)
		(fp_line
			(start 3.24993 -3.24993)
			(end 3.24993 -2.2352)
			(stroke
				(width 0.1524)
				(type default)
			)
			(layer "F.SilkS")
		)
		(fp_line
			(start -3.24993 -3.24993)
			(end 3.24993 -3.24993)
			(stroke
				(width 0.1524)
				(type default)
			)
			(layer "F.SilkS")
		)
		(fp_line
			(start -3.24993 -2.2352)
			(end -3.24993 -3.24993)
			(stroke
				(width 0.1524)
				(type default)
			)
			(layer "F.SilkS")
		)
		(fp_line
			(start 3.24993 2.2352)
			(end 3.24993 3.24993)
			(stroke
				(width 0.1524)
				(type default)
			)
			(layer "F.SilkS")
		)
		(fp_line
			(start 3.24993 3.24993)
			(end 0.201422 3.24993)
			(stroke
				(width 0.1524)
				(type default)
			)
			(layer "F.SilkS")
		)
		(fp_line
			(start -0.814578 3.24993)
			(end -3.24993 3.24993)
			(stroke
				(width 0.1524)
				(type default)
			)
			(layer "F.SilkS")
		)
		(fp_line
			(start -3.24993 3.24993)
			(end -3.24993 2.2352)
			(stroke
				(width 0.1524)
				(type default)
			)
			(layer "F.SilkS")
		)
		(fp_line
			(start 3.24993 -3.24993)
			(end 3.24993 3.24993)
			(stroke
				(width 0.1)
				(type default)
			)
			(layer "F.Fab")
		)
		(fp_line
			(start -3.24993 -3.24993)
			(end 3.24993 -3.24993)
			(stroke
				(width 0.1)
				(type default)
			)
			(layer "F.Fab")
		)
		(fp_line
			(start 3.24993 3.24993)
			(end -3.24993 3.24993)
			(stroke
				(width 0.1)
				(type default)
			)
			(layer "F.Fab")
		)
		(fp_line
			(start -3.24993 3.24993)
			(end -3.24993 -3.24993)
			(stroke
				(width 0.1)
				(type default)
			)
			(layer "F.Fab")
		)
		(pad "1" smd rect
			(at -2.29997 0 90)
			(size 2.0066 4.2164)
			(layers "F.Cu" "F.Mask" "F.Paste")
			(net "IND_P0_CPL7")
		)
		(pad "2" smd rect
			(at 2.29997 0 90)
			(size 2.0066 4.2164)
			(layers "F.Cu" "F.Mask" "F.Paste")
			(net "GND")
		)
	)
	(footprint ""
		(layer "F.Cu")
		(at 161.163 -20.665948 -90)
		(property "Reference" "R4509"
			(at 0 0 270)
			(layer "F.SilkS")
			(hide yes)
			(effects
				(font
					(size 1.27 1.27)
				)
			)
		)
		(property "Value" ""
			(at 0 0 270)
			(layer "F.Fab")
			(effects
				(font
					(size 1.27 1.27)
				)
			)
		)
		(duplicate_pad_numbers_are_jumpers no)
		(fp_line
			(start -0.7874 0.4064)
			(end -0.7874 -0.4064)
			(stroke
				(width 0.1524)
				(type default)
			)
			(layer "F.SilkS")
		)
		(fp_line
			(start 0.7874 0.4064)
			(end -0.7874 0.4064)
			(stroke
				(width 0.1524)
				(type default)
			)
			(layer "F.SilkS")
		)
		(fp_line
			(start -0.7874 -0.4064)
			(end 0.7874 -0.4064)
			(stroke
				(width 0.1524)
				(type default)
			)
			(layer "F.SilkS")
		)
		(fp_line
			(start 0.7874 -0.4064)
			(end 0.7874 0.4064)
			(stroke
				(width 0.1524)
				(type default)
			)
			(layer "F.SilkS")
		)
		(fp_line
			(start -0.67945 0.3048)
			(end -0.67945 -0.305054)
			(stroke
				(width 0.1)
				(type default)
			)
			(layer "F.Fab")
		)
		(fp_line
			(start -0.12065 0.3048)
			(end -0.67945 0.3048)
			(stroke
				(width 0.1)
				(type default)
			)
			(layer "F.Fab")
		)
		(fp_line
			(start 0.120396 0.3048)
			(end 0.120396 0.2794)
			(stroke
				(width 0.1)
				(type default)
			)
			(layer "F.Fab")
		)
		(fp_line
			(start 0.67945 0.3048)
			(end 0.120396 0.3048)
			(stroke
				(width 0.1)
				(type default)
			)
			(layer "F.Fab")
		)
		(fp_line
			(start -0.12065 0.2794)
			(end -0.12065 0.3048)
			(stroke
				(width 0.1)
				(type default)
			)
			(layer "F.Fab")
		)
		(fp_line
			(start 0.120396 0.2794)
			(end -0.12065 0.2794)
			(stroke
				(width 0.1)
				(type default)
			)
			(layer "F.Fab")
		)
		(fp_line
			(start -0.12065 -0.2794)
			(end 0.12065 -0.2794)
			(stroke
				(width 0.1)
				(type default)
			)
			(layer "F.Fab")
		)
		(fp_line
			(start 0.12065 -0.2794)
			(end 0.12065 -0.3048)
			(stroke
				(width 0.1)
				(type default)
			)
			(layer "F.Fab")
		)
		(fp_line
			(start 0.12065 -0.3048)
			(end 0.67945 -0.3048)
			(stroke
				(width 0.1)
				(type default)
			)
			(layer "F.Fab")
		)
		(fp_line
			(start 0.67945 -0.3048)
			(end 0.67945 0.3048)
			(stroke
				(width 0.1)
				(type default)
			)
			(layer "F.Fab")
		)
		(fp_line
			(start -0.67945 -0.305054)
			(end -0.12065 -0.305054)
			(stroke
				(width 0.1)
				(type default)
			)
			(layer "F.Fab")
		)
		(fp_line
			(start -0.12065 -0.305054)
			(end -0.12065 -0.2794)
			(stroke
				(width 0.1)
				(type default)
			)
			(layer "F.Fab")
		)
		(pad "1" smd circle
			(at -0.40005 0 270)
			(size 0 0)
			(layers "F.Cu" "F.Mask" "F.Paste")
			(net "SMB_1_PLD_3V3AUX_SDA")
		)
		(pad "2" smd circle
			(at 0.40005 0 270)
			(size 0 0)
			(layers "F.Cu" "F.Mask" "F.Paste")
			(net "SMB_1_PLD_3V3AUX_SDA_R3")
		)
	)
	(footprint ""
		(layer "F.Cu")
		(at 385.572 -29.581348)
		(property "Reference" "C2346"
			(at 0 0 0)
			(layer "F.SilkS")
			(hide yes)
			(effects
				(font
					(size 1.27 1.27)
				)
			)
		)
		(property "Value" ""
			(at 0 0 0)
			(layer "F.Fab")
			(effects
				(font
					(size 1.27 1.27)
				)
			)
		)
		(duplicate_pad_numbers_are_jumpers no)
		(fp_line
			(start -0.7874 -0.4064)
			(end 0.7874 -0.4064)
			(stroke
				(width 0.1524)
				(type default)
			)
			(layer "F.SilkS")
		)
		(fp_line
			(start -0.7874 0.4064)
			(end -0.7874 -0.4064)
			(stroke
				(width 0.1524)
				(type default)
			)
			(layer "F.SilkS")
		)
		(fp_line
			(start 0.7874 -0.4064)
			(end 0.7874 0.4064)
			(stroke
				(width 0.1524)
				(type default)
			)
			(layer "F.SilkS")
		)
		(fp_line
			(start 0.7874 0.4064)
			(end -0.7874 0.4064)
			(stroke
				(width 0.1524)
				(type default)
			)
			(layer "F.SilkS")
		)
		(fp_line
			(start -0.67945 -0.305054)
			(end -0.12065 -0.305054)
			(stroke
				(width 0.1)
				(type default)
			)
			(layer "F.Fab")
		)
		(fp_line
			(start -0.67945 0.3048)
			(end -0.67945 -0.305054)
			(stroke
				(width 0.1)
				(type default)
			)
			(layer "F.Fab")
		)
		(fp_line
			(start -0.12065 -0.305054)
			(end -0.12065 -0.2794)
			(stroke
				(width 0.1)
				(type default)
			)
			(layer "F.Fab")
		)
		(fp_line
			(start -0.12065 -0.2794)
			(end 0.12065 -0.2794)
			(stroke
				(width 0.1)
				(type default)
			)
			(layer "F.Fab")
		)
		(fp_line
			(start -0.12065 0.2794)
			(end -0.12065 0.3048)
			(stroke
				(width 0.1)
				(type default)
			)
			(layer "F.Fab")
		)
		(fp_line
			(start -0.12065 0.3048)
			(end -0.67945 0.3048)
			(stroke
				(width 0.1)
				(type default)
			)
			(layer "F.Fab")
		)
		(fp_line
			(start 0.120396 0.2794)
			(end -0.12065 0.2794)
			(stroke
				(width 0.1)
				(type default)
			)
			(layer "F.Fab")
		)
		(fp_line
			(start 0.120396 0.3048)
			(end 0.120396 0.2794)
			(stroke
				(width 0.1)
				(type default)
			)
			(layer "F.Fab")
		)
		(fp_line
			(start 0.12065 -0.3048)
			(end 0.67945 -0.3048)
			(stroke
				(width 0.1)
				(type default)
			)
			(layer "F.Fab")
		)
		(fp_line
			(start 0.12065 -0.2794)
			(end 0.12065 -0.3048)
			(stroke
				(width 0.1)
				(type default)
			)
			(layer "F.Fab")
		)
		(fp_line
			(start 0.67945 -0.3048)
			(end 0.67945 0.3048)
			(stroke
				(width 0.1)
				(type default)
			)
			(layer "F.Fab")
		)
		(fp_line
			(start 0.67945 0.3048)
			(end 0.120396 0.3048)
			(stroke
				(width 0.1)
				(type default)
			)
			(layer "F.Fab")
		)
		(pad "1" smd circle
			(at -0.40005 0)
			(size 0 0)
			(layers "F.Cu" "F.Mask" "F.Paste")
			(net "P3V3_AUX")
		)
		(pad "2" smd circle
			(at 0.40005 0)
			(size 0 0)
			(layers "F.Cu" "F.Mask" "F.Paste")
			(net "GND")
		)
	)
	(footprint ""
		(layer "F.Cu")
		(at 129.639822 -337.126326)
		(property "Reference" "PU26_P1_5"
			(at -3.267202 -6.948932 0)
			(unlocked yes)
			(layer "F.SilkS")
			(effects
				(font
					(size 0.7874 0.5842)
					(thickness 0.1524)
				)
				(justify left)
			)
		)
		(property "Value" ""
			(at 0 0 0)
			(layer "F.Fab")
			(effects
				(font
					(size 1.27 1.27)
				)
			)
		)
		(duplicate_pad_numbers_are_jumpers no)
		(fp_line
			(start -2.500122 -2.999994)
			(end -2.24409 -2.999994)
			(stroke
				(width 0.1524)
				(type default)
			)
			(layer "F.SilkS")
		)
		(fp_line
			(start -2.500122 -2.529078)
			(end -2.500122 -2.999994)
			(stroke
				(width 0.1524)
				(type default)
			)
			(layer "F.SilkS")
		)
		(fp_line
			(start -2.500122 0.6604)
			(end -2.500122 0.229108)
			(stroke
				(width 0.1524)
				(type default)
			)
			(layer "F.SilkS")
		)
		(fp_line
			(start -2.500122 2.999994)
			(end -2.500122 2.339594)
			(stroke
				(width 0.1524)
				(type default)
			)
			(layer "F.SilkS")
		)
		(fp_line
			(start -2.2987 2.999994)
			(end -2.500122 2.999994)
			(stroke
				(width 0.1524)
				(type default)
			)
			(layer "F.SilkS")
		)
		(fp_line
			(start 2.31394 -2.999994)
			(end 2.500122 -2.999994)
			(stroke
				(width 0.1524)
				(type default)
			)
			(layer "F.SilkS")
		)
		(fp_line
			(start 2.500122 -2.999994)
			(end 2.500122 -2.44348)
			(stroke
				(width 0.1524)
				(type default)
			)
			(layer "F.SilkS")
		)
		(fp_line
			(start 2.500122 2.339594)
			(end 2.500122 2.999994)
			(stroke
				(width 0.1524)
				(type default)
			)
			(layer "F.SilkS")
		)
		(fp_line
			(start 2.500122 2.999994)
			(end 2.2987 2.999994)
			(stroke
				(width 0.1524)
				(type default)
			)
			(layer "F.SilkS")
		)
		(fp_poly
			(pts
				(xy -2.181606 -3.555492) (xy -2.689606 -2.539492) (xy -3.197606 -3.555492)
			)
			(stroke
				(width 0)
				(type default)
			)
			(fill yes)
			(layer "F.SilkS")
		)
		(fp_line
			(start -2.500122 -2.999994)
			(end 2.500122 -2.999994)
			(stroke
				(width 0.1)
				(type default)
			)
			(layer "F.Fab")
		)
		(fp_line
			(start -2.500122 2.999994)
			(end -2.500122 -2.999994)
			(stroke
				(width 0.1)
				(type default)
			)
			(layer "F.Fab")
		)
		(fp_line
			(start 2.500122 -2.999994)
			(end 2.500122 2.999994)
			(stroke
				(width 0.1)
				(type default)
			)
			(layer "F.Fab")
		)
		(fp_line
			(start 2.500122 2.999994)
			(end -2.500122 2.999994)
			(stroke
				(width 0.1)
				(type default)
			)
			(layer "F.Fab")
		)
		(fp_poly
			(pts
				(xy -4.218432 -2.783078) (xy -4.218432 -1.767078) (xy -3.202432 -2.275078)
			)
			(stroke
				(width 0)
				(type default)
			)
			(fill yes)
			(layer "F.Fab")
		)
		(pad "1" smd rect
			(at -2.400046 -2.275078 90)
			(size 0.2286 0.6096)
			(layers "F.Cu" "F.Mask" "F.Paste")
			(net "PVCCIN_CPU1_VOS5")
		)
		(pad "2" smd rect
			(at -2.400046 -1.82499 90)
			(size 0.2286 0.6096)
			(layers "F.Cu" "F.Mask" "F.Paste")
			(net "GND")
		)
		(pad "3" smd rect
			(at -2.400046 -1.374902 90)
			(size 0.2286 0.6096)
			(layers "F.Cu" "F.Mask" "F.Paste")
			(net "PVCCIN_CPU1_VDD5")
		)
		(pad "4" smd rect
			(at -2.400046 -0.925068 90)
			(size 0.2286 0.6096)
			(layers "F.Cu" "F.Mask" "F.Paste")
			(net "PVCCIN_CPU1_PVCC")
		)
		(pad "5" smd rect
			(at -2.400046 -0.47498 90)
			(size 0.2286 0.6096)
			(layers "F.Cu" "F.Mask" "F.Paste")
			(net "GND")
		)
		(pad "6" smd rect
			(at -2.400046 -0.024892 90)
			(size 0.2286 0.6096)
			(layers "F.Cu" "F.Mask" "F.Paste")
			(net "Net_8532")
		)
		(pad "7_9-20_24" smd circle
			(at 0 1.150112 90)
			(size 0 0)
			(layers "F.Cu" "F.Mask" "F.Paste")
			(net "GND")
		)
		(pad "10_19" smd rect
			(at 0 2.899918 90)
			(size 0.6096 4.318)
			(layers "F.Cu" "F.Mask" "F.Paste")
			(net "SW_PVCCIN_CPU1_SW5")
		)
		(pad "25_29" smd rect
			(at 1.549908 -1.279906 270)
			(size 2.0574 2.3114)
			(layers "F.Cu" "F.Mask" "F.Paste")
			(net "SW_P12V_PVCCIN_CPU1_FLT")
		)
		(pad "30" smd rect
			(at 2.05994 -2.899918)
			(size 0.2286 0.6096)
			(layers "F.Cu" "F.Mask" "F.Paste")
			(net "SW_P12V_PVCCIN_CPU1_FLT")
		)
		(pad "31" smd rect
			(at 1.610106 -2.899918)
			(size 0.2286 0.6096)
			(layers "F.Cu" "F.Mask" "F.Paste")
			(net "Net_8533")
		)
		(pad "32" smd rect
			(at 1.160018 -2.899918)
			(size 0.2286 0.6096)
			(layers "F.Cu" "F.Mask" "F.Paste")
			(net "SW_PVCCIN_CPU1_BOOTR5")
		)
		(pad "33" smd rect
			(at 0.70993 -2.899918)
			(size 0.2286 0.6096)
			(layers "F.Cu" "F.Mask" "F.Paste")
			(net "SW_PVCCIN_CPU1_BOOT5")
		)
		(pad "34" smd rect
			(at 0.260096 -2.899918)
			(size 0.2286 0.6096)
			(layers "F.Cu" "F.Mask" "F.Paste")
			(net "PVCCIN_CPU1_PWM5")
		)
		(pad "35" smd rect
			(at -0.189992 -2.899918)
			(size 0.2286 0.6096)
			(layers "F.Cu" "F.Mask" "F.Paste")
			(net "PVCCIN_CPU1_VDD5")
		)
		(pad "36" smd rect
			(at -0.64008 -2.899918)
			(size 0.2286 0.6096)
			(layers "F.Cu" "F.Mask" "F.Paste")
			(net "PVCCIN_CPU1_ATSEN")
		)
		(pad "37" smd rect
			(at -1.089914 -2.899918)
			(size 0.2286 0.6096)
			(layers "F.Cu" "F.Mask" "F.Paste")
			(net "PVCCIN_CPU1_LSET5")
		)
		(pad "38" smd rect
			(at -1.540002 -2.899918)
			(size 0.2286 0.6096)
			(layers "F.Cu" "F.Mask" "F.Paste")
			(net "PVCCIN_CPU1_IMON5")
		)
		(pad "39" smd rect
			(at -1.99009 -2.899918)
			(size 0.2286 0.6096)
			(layers "F.Cu" "F.Mask" "F.Paste")
			(net "PVCCIN_CPU1_VREF")
		)
		(pad "40" smd rect
			(at -0.87503 -1.27508)
			(size 1.7526 1.9558)
			(layers "F.Cu" "F.Mask" "F.Paste")
			(net "GND")
		)
		(pad "41" smd rect
			(at -1.525016 0.249936 270)
			(size 0.3048 0.4572)
			(layers "F.Cu" "F.Mask" "F.Paste")
			(net "Net_8531")
		)
		(zone
			(layer "F.Cu")
			(hatch none 0.5)
			(connect_pads
				(clearance 0)
			)
			(min_thickness 0.25)
			(keepout
				(tracks not_allowed)
				(vias allowed)
				(pads allowed)
				(copperpour not_allowed)
				(footprints allowed)
			)
			(placement
				(enabled no)
				(sheetname "")
			)
			(fill
				(thermal_gap 0.5)
				(thermal_bridge_width 0.5)
				(island_removal_mode 0)
			)
			(polygon
				(pts
					(xy 127.595376 -338.699348) (xy 127.837692 -338.699348) (xy 127.837692 -337.746848) (xy 127.595376 -337.746848)
				)
			)
		)
		(zone
			(layer "F.Cu")
			(hatch none 0.5)
			(connect_pads
				(clearance 0)
			)
			(min_thickness 0.25)
			(keepout
				(tracks not_allowed)
				(vias allowed)
				(pads allowed)
				(copperpour not_allowed)
				(footprints allowed)
			)
			(placement
				(enabled no)
				(sheetname "")
			)
			(fill
				(thermal_gap 0.5)
				(thermal_bridge_width 0.5)
				(island_removal_mode 0)
			)
			(polygon
				(pts
					(xy 127.1397 -334.126332) (xy 127.1397 -334.875632) (xy 132.139944 -334.875632) (xy 132.139944 -334.126332)
					(xy 131.849622 -334.126332) (xy 131.849622 -334.582008) (xy 127.430022 -334.582008) (xy 127.430022 -334.126332)
				)
			)
		)
	)
	(footprint ""
		(layer "F.Cu")
		(at 502.47169 -469.569546)
		(property "Reference" "JP15_23"
			(at -1.6764 -1.07823 0)
			(unlocked yes)
			(layer "F.SilkS")
			(effects
				(font
					(size 0.7874 0.5842)
					(thickness 0.1524)
				)
				(justify left)
			)
		)
		(property "Value" ""
			(at 0 0 0)
			(layer "F.Fab")
			(effects
				(font
					(size 1.27 1.27)
				)
			)
		)
		(duplicate_pad_numbers_are_jumpers no)
		(pad "1" smd circle
			(at 0 0)
			(size 0.762 0.762)
			(layers "F.Cu" "F.Mask" "F.Paste")
			(net "Net_8622")
		)
	)
	(footprint ""
		(layer "F.Cu")
		(at 285.714948 -411.2895 90)
		(property "Reference" "R4554"
			(at 0 0 90)
			(layer "F.SilkS")
			(hide yes)
			(effects
				(font
					(size 1.27 1.27)
				)
			)
		)
		(property "Value" ""
			(at 0 0 90)
			(layer "F.Fab")
			(effects
				(font
					(size 1.27 1.27)
				)
			)
		)
		(duplicate_pad_numbers_are_jumpers no)
		(fp_line
			(start 0.7874 -0.4064)
			(end 0.7874 0.4064)
			(stroke
				(width 0.1524)
				(type default)
			)
			(layer "F.SilkS")
		)
		(fp_line
			(start -0.7874 -0.4064)
			(end 0.7874 -0.4064)
			(stroke
				(width 0.1524)
				(type default)
			)
			(layer "F.SilkS")
		)
		(fp_line
			(start 0.7874 0.4064)
			(end -0.7874 0.4064)
			(stroke
				(width 0.1524)
				(type default)
			)
			(layer "F.SilkS")
		)
		(fp_line
			(start -0.7874 0.4064)
			(end -0.7874 -0.4064)
			(stroke
				(width 0.1524)
				(type default)
			)
			(layer "F.SilkS")
		)
		(fp_line
			(start -0.12065 -0.305054)
			(end -0.12065 -0.2794)
			(stroke
				(width 0.1)
				(type default)
			)
			(layer "F.Fab")
		)
		(fp_line
			(start -0.67945 -0.305054)
			(end -0.12065 -0.305054)
			(stroke
				(width 0.1)
				(type default)
			)
			(layer "F.Fab")
		)
		(fp_line
			(start 0.67945 -0.3048)
			(end 0.67945 0.3048)
			(stroke
				(width 0.1)
				(type default)
			)
			(layer "F.Fab")
		)
		(fp_line
			(start 0.12065 -0.3048)
			(end 0.67945 -0.3048)
			(stroke
				(width 0.1)
				(type default)
			)
			(layer "F.Fab")
		)
		(fp_line
			(start 0.12065 -0.2794)
			(end 0.12065 -0.3048)
			(stroke
				(width 0.1)
				(type default)
			)
			(layer "F.Fab")
		)
		(fp_line
			(start -0.12065 -0.2794)
			(end 0.12065 -0.2794)
			(stroke
				(width 0.1)
				(type default)
			)
			(layer "F.Fab")
		)
		(fp_line
			(start 0.120396 0.2794)
			(end -0.12065 0.2794)
			(stroke
				(width 0.1)
				(type default)
			)
			(layer "F.Fab")
		)
		(fp_line
			(start -0.12065 0.2794)
			(end -0.12065 0.3048)
			(stroke
				(width 0.1)
				(type default)
			)
			(layer "F.Fab")
		)
		(fp_line
			(start 0.67945 0.3048)
			(end 0.120396 0.3048)
			(stroke
				(width 0.1)
				(type default)
			)
			(layer "F.Fab")
		)
		(fp_line
			(start 0.120396 0.3048)
			(end 0.120396 0.2794)
			(stroke
				(width 0.1)
				(type default)
			)
			(layer "F.Fab")
		)
		(fp_line
			(start -0.12065 0.3048)
			(end -0.67945 0.3048)
			(stroke
				(width 0.1)
				(type default)
			)
			(layer "F.Fab")
		)
		(fp_line
			(start -0.67945 0.3048)
			(end -0.67945 -0.305054)
			(stroke
				(width 0.1)
				(type default)
			)
			(layer "F.Fab")
		)
		(pad "1" smd circle
			(at -0.40005 0 90)
			(size 0 0)
			(layers "F.Cu" "F.Mask" "F.Paste")
			(net "P3V3_AUX")
		)
		(pad "2" smd circle
			(at 0.40005 0 90)
			(size 0 0)
			(layers "F.Cu" "F.Mask" "F.Paste")
			(net "HPDB_HSC_PWRGD_ISO")
		)
	)
)
